# T6G (Grand Teton) — schematic netlist excerpt (pin names and nets, part order shuffled) for the footprints in the layout excerpt that follows; sources: Cadence DE-HDL packaged netlist, KiCad conversion of 04192023_DAF0TMB3IC0_F0TG_MB_C_brd_V02_OCP.brd

R8080  Q_RES  0 5% CHIP  pkg 0402LF  page 86 : A = PWRGD_CHAF_CPU0 ; B = PWRGD_CHAF_CPU0_R1

(kicad_pcb
	(version 20260206)
	(generator "pcbnew")
	(generator_version "10.0")
	(general
		(thickness 1.6)
		(legacy_teardrops no)
	)
	(paper "A4")
	(title_block
		(title "04192023_DAF0TMB3IC0_F0TG_MB_C_brd_V02_OCP.brd")
		(comment 1 "Grand Teton / footprints 582-582 of 8354")
	)
	(layers
		(0 "F.Cu" signal "TOP")
		(4 "In1.Cu" signal "GND")
		(6 "In2.Cu" signal "IN1")
		(8 "In3.Cu" signal "GND1")
		(10 "In4.Cu" signal "IN2")
		(12 "In5.Cu" signal "GND2")
		(14 "In6.Cu" signal "IN3")
		(16 "In7.Cu" signal "GND3")
		(18 "In8.Cu" signal "VCC")
		(20 "In9.Cu" signal "VCC1")
		(22 "In10.Cu" signal "GND4")
		(24 "In11.Cu" signal "IN4")
		(26 "In12.Cu" signal "GND5")
		(28 "In13.Cu" signal "IN5")
		(30 "In14.Cu" signal "GND6")
		(32 "In15.Cu" signal "IN6")
		(34 "In16.Cu" signal "GND7")
		(2 "B.Cu" signal "BOTTOM")
		(9 "F.Adhes" user "F.Adhesive")
		(11 "B.Adhes" user "B.Adhesive")
		(13 "F.Paste" user "Package Geometry/Pastemask Top")
		(15 "B.Paste" user "Package Geometry/Pastemask Bottom")
		(5 "F.SilkS" user "Ref Des/Silkscreen Top")
		(7 "B.SilkS" user "Ref Des/Silkscreen Bottom")
		(1 "F.Mask" user "Board Geometry/Soldermask Top")
		(3 "B.Mask" user "Board Geometry/Soldermask Bottom")
		(17 "Dwgs.User" user "User.Drawings")
		(19 "Cmts.User" user "User.Comments")
		(21 "Eco1.User" user "User.Eco1")
		(23 "Eco2.User" user "User.Eco2")
		(25 "Edge.Cuts" user "Board Geometry/Outline")
		(27 "Margin" user)
		(31 "F.CrtYd" user "Package Geometry/Place Bound Top")
		(29 "B.CrtYd" user "Package Geometry/Place Bound Bottom")
		(35 "F.Fab" user "Ref Des/Assembly Top")
		(33 "B.Fab" user "Ref Des/Assembly Bottom")
	)
	(footprint ""
		(layer "F.Cu")
		(at 208.661 -104.013 180)
		(property "Reference" "R8080"
			(at 0 0 180)
			(layer "F.SilkS")
			(hide yes)
			(effects
				(font
					(size 1.27 1.27)
				)
			)
		)
		(property "Value" ""
			(at 0 0 180)
			(layer "F.Fab")
			(effects
				(font
					(size 1.27 1.27)
				)
			)
		)
		(duplicate_pad_numbers_are_jumpers no)
		(fp_line
			(start 0.7874 0.4064)
			(end -0.7874 0.4064)
			(stroke
				(width 0.1524)
				(type default)
			)
			(layer "F.SilkS")
		)
		(fp_line
			(start 0.7874 -0.4064)
			(end 0.7874 0.4064)
			(stroke
				(width 0.1524)
				(type default)
			)
			(layer "F.SilkS")
		)
		(fp_line
			(start -0.7874 0.4064)
			(end -0.7874 -0.4064)
			(stroke
				(width 0.1524)
				(type default)
			)
			(layer "F.SilkS")
		)
		(fp_line
			(start -0.7874 -0.4064)
			(end 0.7874 -0.4064)
			(stroke
				(width 0.1524)
				(type default)
			)
			(layer "F.SilkS")
		)
		(fp_line
			(start 0.67945 0.3048)
			(end 0.120396 0.3048)
			(stroke
				(width 0.1)
				(type default)
			)
			(layer "F.Fab")
		)
		(fp_line
			(start 0.67945 -0.3048)
			(end 0.67945 0.3048)
			(stroke
				(width 0.1)
				(type default)
			)
			(layer "F.Fab")
		)
		(fp_line
			(start 0.12065 -0.2794)
			(end 0.12065 -0.3048)
			(stroke
				(width 0.1)
				(type default)
			)
			(layer "F.Fab")
		)
		(fp_line
			(start 0.12065 -0.3048)
			(end 0.67945 -0.3048)
			(stroke
				(width 0.1)
				(type default)
			)
			(layer "F.Fab")
		)
		(fp_line
			(start 0.120396 0.3048)
			(end 0.120396 0.2794)
			(stroke
				(width 0.1)
				(type default)
			)
			(layer "F.Fab")
		)
		(fp_line
			(start 0.120396 0.2794)
			(end -0.12065 0.2794)
			(stroke
				(width 0.1)
				(type default)
			)
			(layer "F.Fab")
		)
		(fp_line
			(start -0.12065 0.3048)
			(end -0.67945 0.3048)
			(stroke
				(width 0.1)
				(type default)
			)
			(layer "F.Fab")
		)
		(fp_line
			(start -0.12065 0.2794)
			(end -0.12065 0.3048)
			(stroke
				(width 0.1)
				(type default)
			)
			(layer "F.Fab")
		)
		(fp_line
			(start -0.12065 -0.2794)
			(end 0.12065 -0.2794)
			(stroke
				(width 0.1)
				(type default)
			)
			(layer "F.Fab")
		)
		(fp_line
			(start -0.12065 -0.305054)
			(end -0.12065 -0.2794)
			(stroke
				(width 0.1)
				(type default)
			)
			(layer "F.Fab")
		)
		(fp_line
			(start -0.67945 0.3048)
			(end -0.67945 -0.305054)
			(stroke
				(width 0.1)
				(type default)
			)
			(layer "F.Fab")
		)
		(fp_line
			(start -0.67945 -0.305054)
			(end -0.12065 -0.305054)
			(stroke
				(width 0.1)
				(type default)
			)
			(layer "F.Fab")
		)
		(pad "1" smd circle
			(at -0.40005 0 180)
			(size 0 0)
			(layers "F.Cu" "F.Mask" "F.Paste")
			(net "PWRGD_CHAF_CPU0")
		)
		(pad "2" smd circle
			(at 0.40005 0 180)
			(size 0 0)
			(layers "F.Cu" "F.Mask" "F.Paste")
			(net "PWRGD_CHAF_CPU0_R1")
		)
	)
)
